# S9S_MB_2U (Grand Teton) — schematic netlist excerpt (pin names and nets, part order shuffled) for the footprints in the layout excerpt that follows; sources: Cadence DE-HDL packaged netlist, KiCad conversion of 03242023_DA0F0TMBIJ0_F0T_Motherboard_J_brd_V01_OCP.brd

R1270  Q_RES  240 1% EMPTY  pkg 0402LF  page 44 : A = PD_CPU1_PROCDIS_COD_GTL_N ; B = GND
PC535_P1_4  Q_CAP  22UF 16V 20% X6S  pkg C0805  page 286 : A = SW_P12V_PVCCIN_CPU1_FLT ; B = GND
R4721  Q_RES  0 5% CHIP  pkg 0402LF  page 245 : A = FM_AC_PWR_BTN_R_N ; B = FM_AC_PWR_BTN_PDB_N

(kicad_pcb
	(version 20260206)
	(generator "pcbnew")
	(generator_version "10.0")
	(general
		(thickness 1.6)
		(legacy_teardrops no)
	)
	(paper "A4")
	(title_block
		(title "03242023_DA0F0TMBIJ0_F0T_Motherboard_J_brd_V01_OCP.brd")
		(comment 1 "Grand Teton / footprints 4670-4672 of 6105")
	)
	(layers
		(0 "F.Cu" signal "TOP")
		(4 "In1.Cu" signal "GND")
		(6 "In2.Cu" signal "IN1")
		(8 "In3.Cu" signal "GND1")
		(10 "In4.Cu" signal "IN2")
		(12 "In5.Cu" signal "GND2")
		(14 "In6.Cu" signal "IN3")
		(16 "In7.Cu" signal "GND3")
		(18 "In8.Cu" signal "VCC")
		(20 "In9.Cu" signal "VCC1")
		(22 "In10.Cu" signal "GND4")
		(24 "In11.Cu" signal "IN4")
		(26 "In12.Cu" signal "GND5")
		(28 "In13.Cu" signal "IN5")
		(30 "In14.Cu" signal "GND6")
		(32 "In15.Cu" signal "IN6")
		(34 "In16.Cu" signal "GND7")
		(2 "B.Cu" signal "BOTTOM")
		(9 "F.Adhes" user "F.Adhesive")
		(11 "B.Adhes" user "B.Adhesive")
		(13 "F.Paste" user "Package Geometry/Pastemask Top")
		(15 "B.Paste" user "Package Geometry/Pastemask Bottom")
		(5 "F.SilkS" user "Ref Des/Silkscreen Top")
		(7 "B.SilkS" user "Ref Des/Silkscreen Bottom")
		(1 "F.Mask" user "Board Geometry/Soldermask Top")
		(3 "B.Mask" user "Board Geometry/Soldermask Bottom")
		(17 "Dwgs.User" user "User.Drawings")
		(19 "Cmts.User" user "User.Comments")
		(21 "Eco1.User" user "User.Eco1")
		(23 "Eco2.User" user "User.Eco2")
		(25 "Edge.Cuts" user "Board Geometry/Outline")
		(27 "Margin" user)
		(31 "F.CrtYd" user "Package Geometry/Place Bound Top")
		(29 "B.CrtYd" user "Package Geometry/Place Bound Bottom")
		(35 "F.Fab" user "Ref Des/Assembly Top")
		(33 "B.Fab" user "Ref Des/Assembly Bottom")
	)
	(footprint ""
		(layer "B.Cu")
		(at 166.301166 -247.250712 180)
		(property "Reference" "R1270"
			(at 0 0 0)
			(layer "B.SilkS")
			(hide yes)
			(effects
				(font
					(size 1.27 1.27)
				)
				(justify mirror)
			)
		)
		(property "Value" ""
			(at 0 0 0)
			(layer "B.Fab")
			(effects
				(font
					(size 1.27 1.27)
				)
				(justify mirror)
			)
		)
		(duplicate_pad_numbers_are_jumpers no)
		(fp_line
			(start 0.7874 0.4064)
			(end 0.7874 -0.4064)
			(stroke
				(width 0.1524)
				(type default)
			)
			(layer "B.SilkS")
		)
		(fp_line
			(start 0.7874 -0.4064)
			(end -0.7874 -0.4064)
			(stroke
				(width 0.1524)
				(type default)
			)
			(layer "B.SilkS")
		)
		(fp_line
			(start -0.7874 0.4064)
			(end 0.7874 0.4064)
			(stroke
				(width 0.1524)
				(type default)
			)
			(layer "B.SilkS")
		)
		(fp_line
			(start -0.7874 -0.4064)
			(end -0.7874 0.4064)
			(stroke
				(width 0.1524)
				(type default)
			)
			(layer "B.SilkS")
		)
		(fp_line
			(start 0.67945 0.3048)
			(end 0.67945 -0.305054)
			(stroke
				(width 0.1)
				(type default)
			)
			(layer "B.Fab")
		)
		(fp_line
			(start 0.67945 -0.305054)
			(end 0.12065 -0.305054)
			(stroke
				(width 0.1)
				(type default)
			)
			(layer "B.Fab")
		)
		(fp_line
			(start 0.12065 0.3048)
			(end 0.67945 0.3048)
			(stroke
				(width 0.1)
				(type default)
			)
			(layer "B.Fab")
		)
		(fp_line
			(start 0.12065 0.2794)
			(end 0.12065 0.3048)
			(stroke
				(width 0.1)
				(type default)
			)
			(layer "B.Fab")
		)
		(fp_line
			(start 0.12065 -0.2794)
			(end -0.12065 -0.2794)
			(stroke
				(width 0.1)
				(type default)
			)
			(layer "B.Fab")
		)
		(fp_line
			(start 0.12065 -0.305054)
			(end 0.12065 -0.2794)
			(stroke
				(width 0.1)
				(type default)
			)
			(layer "B.Fab")
		)
		(fp_line
			(start -0.120396 0.3048)
			(end -0.120396 0.2794)
			(stroke
				(width 0.1)
				(type default)
			)
			(layer "B.Fab")
		)
		(fp_line
			(start -0.120396 0.2794)
			(end 0.12065 0.2794)
			(stroke
				(width 0.1)
				(type default)
			)
			(layer "B.Fab")
		)
		(fp_line
			(start -0.12065 -0.2794)
			(end -0.12065 -0.3048)
			(stroke
				(width 0.1)
				(type default)
			)
			(layer "B.Fab")
		)
		(fp_line
			(start -0.12065 -0.3048)
			(end -0.67945 -0.3048)
			(stroke
				(width 0.1)
				(type default)
			)
			(layer "B.Fab")
		)
		(fp_line
			(start -0.67945 0.3048)
			(end -0.120396 0.3048)
			(stroke
				(width 0.1)
				(type default)
			)
			(layer "B.Fab")
		)
		(fp_line
			(start -0.67945 -0.3048)
			(end -0.67945 0.3048)
			(stroke
				(width 0.1)
				(type default)
			)
			(layer "B.Fab")
		)
		(pad "1" smd circle
			(at 0.40005 0)
			(size 0 0)
			(layers "B.Cu" "B.Mask" "B.Paste")
			(net "PD_CPU1_PROCDIS_COD_GTL_N")
		)
		(pad "2" smd circle
			(at -0.40005 0)
			(size 0 0)
			(layers "B.Cu" "B.Mask" "B.Paste")
			(net "GND")
		)
	)
	(footprint ""
		(layer "B.Cu")
		(at 124.736098 -333.73568 90)
		(property "Reference" "PC535_P1_4"
			(at 0 0 90)
			(layer "B.SilkS")
			(hide yes)
			(effects
				(font
					(size 1.27 1.27)
				)
				(justify mirror)
			)
		)
		(property "Value" ""
			(at 0 0 90)
			(layer "B.Fab")
			(effects
				(font
					(size 1.27 1.27)
				)
				(justify mirror)
			)
		)
		(duplicate_pad_numbers_are_jumpers no)
		(fp_line
			(start 1.524 -0.762)
			(end -1.524 -0.762)
			(stroke
				(width 0.1524)
				(type default)
			)
			(layer "B.SilkS")
		)
		(fp_line
			(start -1.524 -0.762)
			(end -1.524 0.762)
			(stroke
				(width 0.1524)
				(type default)
			)
			(layer "B.SilkS")
		)
		(fp_line
			(start 1.524 0.762)
			(end 1.524 -0.762)
			(stroke
				(width 0.1524)
				(type default)
			)
			(layer "B.SilkS")
		)
		(fp_line
			(start -1.524 0.762)
			(end 1.524 0.762)
			(stroke
				(width 0.1524)
				(type default)
			)
			(layer "B.SilkS")
		)
		(fp_line
			(start 1.1049 -0.724916)
			(end 1.1049 0.724916)
			(stroke
				(width 0.1)
				(type default)
			)
			(layer "B.Fab")
		)
		(fp_line
			(start -1.1049 -0.724916)
			(end 1.1049 -0.724916)
			(stroke
				(width 0.1)
				(type default)
			)
			(layer "B.Fab")
		)
		(fp_line
			(start 1.1049 0.724916)
			(end -1.1049 0.724916)
			(stroke
				(width 0.1)
				(type default)
			)
			(layer "B.Fab")
		)
		(fp_line
			(start -1.1049 0.724916)
			(end -1.1049 -0.724916)
			(stroke
				(width 0.1)
				(type default)
			)
			(layer "B.Fab")
		)
		(pad "1" smd rect
			(at 0.889 0 90)
			(size 1.016 1.27)
			(layers "B.Cu" "B.Mask" "B.Paste")
			(net "SW_P12V_PVCCIN_CPU1_FLT")
		)
		(pad "2" smd rect
			(at -0.889 0 90)
			(size 1.016 1.27)
			(layers "B.Cu" "B.Mask" "B.Paste")
			(net "GND")
		)
	)
	(footprint ""
		(layer "B.Cu")
		(at 232.283 -423.0116 -90)
		(property "Reference" "R4721"
			(at 0 0 90)
			(layer "B.SilkS")
			(hide yes)
			(effects
				(font
					(size 1.27 1.27)
				)
				(justify mirror)
			)
		)
		(property "Value" ""
			(at 0 0 90)
			(layer "B.Fab")
			(effects
				(font
					(size 1.27 1.27)
				)
				(justify mirror)
			)
		)
		(duplicate_pad_numbers_are_jumpers no)
		(fp_line
			(start -0.7874 0.4064)
			(end 0.7874 0.4064)
			(stroke
				(width 0.1524)
				(type default)
			)
			(layer "B.SilkS")
		)
		(fp_line
			(start 0.7874 0.4064)
			(end 0.7874 -0.4064)
			(stroke
				(width 0.1524)
				(type default)
			)
			(layer "B.SilkS")
		)
		(fp_line
			(start -0.7874 -0.4064)
			(end -0.7874 0.4064)
			(stroke
				(width 0.1524)
				(type default)
			)
			(layer "B.SilkS")
		)
		(fp_line
			(start 0.7874 -0.4064)
			(end -0.7874 -0.4064)
			(stroke
				(width 0.1524)
				(type default)
			)
			(layer "B.SilkS")
		)
		(fp_line
			(start -0.67945 0.3048)
			(end -0.120396 0.3048)
			(stroke
				(width 0.1)
				(type default)
			)
			(layer "B.Fab")
		)
		(fp_line
			(start -0.120396 0.3048)
			(end -0.120396 0.2794)
			(stroke
				(width 0.1)
				(type default)
			)
			(layer "B.Fab")
		)
		(fp_line
			(start 0.12065 0.3048)
			(end 0.67945 0.3048)
			(stroke
				(width 0.1)
				(type default)
			)
			(layer "B.Fab")
		)
		(fp_line
			(start 0.67945 0.3048)
			(end 0.67945 -0.305054)
			(stroke
				(width 0.1)
				(type default)
			)
			(layer "B.Fab")
		)
		(fp_line
			(start -0.120396 0.2794)
			(end 0.12065 0.2794)
			(stroke
				(width 0.1)
				(type default)
			)
			(layer "B.Fab")
		)
		(fp_line
			(start 0.12065 0.2794)
			(end 0.12065 0.3048)
			(stroke
				(width 0.1)
				(type default)
			)
			(layer "B.Fab")
		)
		(fp_line
			(start -0.12065 -0.2794)
			(end -0.12065 -0.3048)
			(stroke
				(width 0.1)
				(type default)
			)
			(layer "B.Fab")
		)
		(fp_line
			(start 0.12065 -0.2794)
			(end -0.12065 -0.2794)
			(stroke
				(width 0.1)
				(type default)
			)
			(layer "B.Fab")
		)
		(fp_line
			(start -0.67945 -0.3048)
			(end -0.67945 0.3048)
			(stroke
				(width 0.1)
				(type default)
			)
			(layer "B.Fab")
		)
		(fp_line
			(start -0.12065 -0.3048)
			(end -0.67945 -0.3048)
			(stroke
				(width 0.1)
				(type default)
			)
			(layer "B.Fab")
		)
		(fp_line
			(start 0.12065 -0.305054)
			(end 0.12065 -0.2794)
			(stroke
				(width 0.1)
				(type default)
			)
			(layer "B.Fab")
		)
		(fp_line
			(start 0.67945 -0.305054)
			(end 0.12065 -0.305054)
			(stroke
				(width 0.1)
				(type default)
			)
			(layer "B.Fab")
		)
		(pad "1" smd circle
			(at 0.40005 0 90)
			(size 0 0)
			(layers "B.Cu" "B.Mask" "B.Paste")
			(net "FM_AC_PWR_BTN_R_N")
		)
		(pad "2" smd circle
			(at -0.40005 0 90)
			(size 0 0)
			(layers "B.Cu" "B.Mask" "B.Paste")
			(net "FM_AC_PWR_BTN_PDB_N")
		)
	)
)
